(kicad_pcb
	(version 20260206)
	(generator "pcbnew")
	(generator_version "10.0")
	(general
		(thickness 1.6)
		(legacy_teardrops no)
	)
	(paper "A4")
	(title_block
		(title "panther-plus-userver — 13130-1b_20150205.brd")
		(comment 1 "Honey Badger (Wiwynn) / footprints 632-639 of 1509")
	)
	(layers
		(0 "F.Cu" signal "TOP")
		(4 "In1.Cu" signal "L2")
		(6 "In2.Cu" signal "L3")
		(8 "In3.Cu" signal "L4")
		(10 "In4.Cu" signal "L5")
		(12 "In5.Cu" signal "L6")
		(14 "In6.Cu" signal "L7")
		(16 "In7.Cu" signal "L8")
		(18 "In8.Cu" signal "L9")
		(20 "In9.Cu" signal "L10")
		(22 "In10.Cu" signal "L11")
		(2 "B.Cu" signal "BOTTOM")
		(9 "F.Adhes" user "F.Adhesive")
		(11 "B.Adhes" user "B.Adhesive")
		(13 "F.Paste" user "Package Geometry/Pastemask Top")
		(15 "B.Paste" user "Package Geometry/Pastemask Bottom")
		(5 "F.SilkS" user "Ref Des/Silkscreen Top")
		(7 "B.SilkS" user "Ref Des/Silkscreen Bottom")
		(1 "F.Mask" user "Board Geometry/Soldermask Top")
		(3 "B.Mask" user "Board Geometry/Soldermask Bottom")
		(17 "Dwgs.User" user "User.Drawings")
		(19 "Cmts.User" user "User.Comments")
		(21 "Eco1.User" user "User.Eco1")
		(23 "Eco2.User" user "User.Eco2")
		(25 "Edge.Cuts" user "Board Geometry/Outline")
		(27 "Margin" user)
		(31 "F.CrtYd" user "Package Geometry/Place Bound Top")
		(29 "B.CrtYd" user "Package Geometry/Place Bound Bottom")
		(35 "F.Fab" user "Ref Des/Assembly Top")
		(33 "B.Fab" user "Ref Des/Assembly Bottom")
	)
	(footprint ""
		(layer "F.Cu")
		(at 100.6094 -66.8274 90)
		(property "Reference" "PR7"
			(at 0 0 90)
			(layer "F.SilkS")
			(hide yes)
			(effects
				(font
					(size 1.27 1.27)
				)
			)
		)
		(property "Value" "10KR2F-2-GP"
			(at 0.064008 -3.993896 90)
			(unlocked yes)
			(layer "F.Fab")
			(hide yes)
			(effects
				(font
					(size 1.016 1.016)
					(thickness 0.1524)
				)
			)
		)
		(property "Device Type" "R402H16"
			(at 0.064008 -5.517896 90)
			(unlocked yes)
			(layer "F.Fab")
			(hide yes)
			(effects
				(font
					(size 1.016 1.016)
					(thickness 0.1524)
				)
			)
		)
		(duplicate_pad_numbers_are_jumpers no)
		(fp_rect
			(start -0.381 0.8382)
			(end 0.381 -0.8382)
			(stroke
				(width 0)
				(type default)
			)
			(fill no)
			(layer "F.CrtYd")
		)
		(fp_rect
			(start -0.381 0.8382)
			(end 0.381 -0.8382)
			(stroke
				(width 0)
				(type default)
			)
			(fill no)
			(layer "F.Fab")
		)
		(pad "1" smd custom
			(at 0 -0.4318 90)
			(size 0.127 0.127)
			(layers "F.Cu" "F.Mask" "F.Paste")
			(net "PWRGD_P1V1_PG")
			(options
				(clearance outline)
				(anchor circle)
			)
			(primitives
				(gr_poly
					(pts
						(arc
							(start -0.2032 -0.2794)
							(mid -0.239121 -0.264521)
							(end -0.254 -0.2286)
						)
						(arc
							(start -0.254 0.2286)
							(mid -0.239121 0.264521)
							(end -0.2032 0.2794)
						)
						(arc
							(start 0.2032 0.2794)
							(mid 0.239121 0.264521)
							(end 0.254 0.2286)
						)
						(arc
							(start 0.254 -0.2286)
							(mid 0.239121 -0.264521)
							(end 0.2032 -0.2794)
						)
					)
					(width 0)
					(fill yes)
				)
			)
		)
		(pad "2" smd custom
			(at 0 0.4318 90)
			(size 0.127 0.127)
			(layers "F.Cu" "F.Mask" "F.Paste")
			(net "P3V3_STBY")
			(options
				(clearance outline)
				(anchor circle)
			)
			(primitives
				(gr_poly
					(pts
						(arc
							(start -0.2032 -0.2794)
							(mid -0.239121 -0.264521)
							(end -0.254 -0.2286)
						)
						(arc
							(start -0.254 0.2286)
							(mid -0.239121 0.264521)
							(end -0.2032 0.2794)
						)
						(arc
							(start 0.2032 0.2794)
							(mid 0.239121 0.264521)
							(end 0.254 0.2286)
						)
						(arc
							(start 0.254 -0.2286)
							(mid 0.239121 -0.264521)
							(end 0.2032 -0.2794)
						)
					)
					(width 0)
					(fill yes)
				)
			)
		)
	)
	(footprint ""
		(layer "F.Cu")
		(at 107.569 -64.262 180)
		(property "Reference" "C8"
			(at 0 0 180)
			(layer "F.SilkS")
			(hide yes)
			(effects
				(font
					(size 1.27 1.27)
				)
			)
		)
		(property "Value" "SCD1U10V2KX-5GP"
			(at 1.1811 -2.7051 180)
			(unlocked yes)
			(layer "F.Fab")
			(hide yes)
			(effects
				(font
					(size 1.016 1.016)
					(thickness 0.1524)
				)
			)
		)
		(property "Device Type" "C402H22"
			(at 1.1811 -4.2291 180)
			(unlocked yes)
			(layer "F.Fab")
			(hide yes)
			(effects
				(font
					(size 1.016 1.016)
					(thickness 0.1524)
				)
			)
		)
		(duplicate_pad_numbers_are_jumpers no)
		(fp_rect
			(start -0.381 0.7366)
			(end 0.381 -0.7366)
			(stroke
				(width 0)
				(type default)
			)
			(fill no)
			(layer "F.CrtYd")
		)
		(fp_rect
			(start -0.381 0.7366)
			(end 0.381 -0.7366)
			(stroke
				(width 0)
				(type default)
			)
			(fill no)
			(layer "F.Fab")
		)
		(pad "1" smd custom
			(at 0 -0.4572 180)
			(size 0.1143 0.1143)
			(layers "F.Cu" "F.Mask" "F.Paste")
			(net "P3V3_STBY")
			(options
				(clearance outline)
				(anchor circle)
			)
			(primitives
				(gr_poly
					(pts
						(arc
							(start -0.254 -0.1778)
							(mid -0.239121 -0.213721)
							(end -0.2032 -0.2286)
						)
						(arc
							(start 0.2032 -0.2286)
							(mid 0.239121 -0.213721)
							(end 0.254 -0.1778)
						)
						(arc
							(start 0.254 0.1778)
							(mid 0.239121 0.213721)
							(end 0.2032 0.2286)
						)
						(arc
							(start -0.2032 0.2286)
							(mid -0.239121 0.213721)
							(end -0.254 0.1778)
						)
					)
					(width 0)
					(fill yes)
				)
			)
		)
		(pad "2" smd custom
			(at 0 0.4572 180)
			(size 0.1143 0.1143)
			(layers "F.Cu" "F.Mask" "F.Paste")
			(net "GND")
			(options
				(clearance outline)
				(anchor circle)
			)
			(primitives
				(gr_poly
					(pts
						(arc
							(start -0.254 -0.1778)
							(mid -0.239121 -0.213721)
							(end -0.2032 -0.2286)
						)
						(arc
							(start 0.2032 -0.2286)
							(mid 0.239121 -0.213721)
							(end 0.254 -0.1778)
						)
						(arc
							(start 0.254 0.1778)
							(mid 0.239121 0.213721)
							(end 0.2032 0.2286)
						)
						(arc
							(start -0.2032 0.2286)
							(mid -0.239121 0.213721)
							(end -0.254 0.1778)
						)
					)
					(width 0)
					(fill yes)
				)
			)
		)
	)
	(footprint ""
		(layer "F.Cu")
		(at 29.083 -32.385 180)
		(property "Reference" "PC36"
			(at 0 0 180)
			(layer "F.SilkS")
			(hide yes)
			(effects
				(font
					(size 1.27 1.27)
				)
			)
		)
		(property "Value" "SC22U6D3V3MX-1-GP"
			(at -0.0254 -2.0193 180)
			(unlocked yes)
			(layer "F.Fab")
			(hide yes)
			(effects
				(font
					(size 1.016 1.016)
					(thickness 0.1524)
				)
			)
		)
		(property "Device Type" "C603H40"
			(at -0.0254 -3.5433 180)
			(unlocked yes)
			(layer "F.Fab")
			(hide yes)
			(effects
				(font
					(size 1.016 1.016)
					(thickness 0.1524)
				)
			)
		)
		(duplicate_pad_numbers_are_jumpers no)
		(fp_line
			(start -0.4064 0)
			(end 0.4064 0)
			(stroke
				(width 0.2286)
				(type default)
			)
			(layer "F.SilkS")
		)
		(fp_rect
			(start -0.635 1.1811)
			(end 0.635 -1.1811)
			(stroke
				(width 0)
				(type default)
			)
			(fill no)
			(layer "F.CrtYd")
		)
		(fp_rect
			(start -0.635 1.1811)
			(end 0.635 -1.1811)
			(stroke
				(width 0)
				(type default)
			)
			(fill no)
			(layer "F.Fab")
		)
		(pad "1" smd custom
			(at 0 -0.6604 180)
			(size 0.19685 0.19685)
			(layers "F.Cu" "F.Mask" "F.Paste")
			(net "P1V0")
			(options
				(clearance outline)
				(anchor circle)
			)
			(primitives
				(gr_poly
					(pts
						(arc
							(start 0.508 -0.2921)
							(mid 0.478242 -0.363942)
							(end 0.4064 -0.3937)
						)
						(arc
							(start -0.4064 -0.3937)
							(mid -0.478242 -0.363942)
							(end -0.508 -0.2921)
						)
						(arc
							(start -0.508 0.2921)
							(mid -0.478242 0.363942)
							(end -0.4064 0.3937)
						)
						(arc
							(start 0.4064 0.3937)
							(mid 0.478242 0.363942)
							(end 0.508 0.2921)
						)
					)
					(width 0)
					(fill yes)
				)
			)
		)
		(pad "2" smd custom
			(at 0 0.6604 180)
			(size 0.19685 0.19685)
			(layers "F.Cu" "F.Mask" "F.Paste")
			(net "GND")
			(options
				(clearance outline)
				(anchor circle)
			)
			(primitives
				(gr_poly
					(pts
						(arc
							(start 0.508 -0.2921)
							(mid 0.478242 -0.363942)
							(end 0.4064 -0.3937)
						)
						(arc
							(start -0.4064 -0.3937)
							(mid -0.478242 -0.363942)
							(end -0.508 -0.2921)
						)
						(arc
							(start -0.508 0.2921)
							(mid -0.478242 0.363942)
							(end -0.4064 0.3937)
						)
						(arc
							(start 0.4064 0.3937)
							(mid 0.478242 0.363942)
							(end 0.508 0.2921)
						)
					)
					(width 0)
					(fill yes)
				)
			)
		)
	)
	(footprint ""
		(layer "F.Cu")
		(at 116.967 -39.3954 90)
		(property "Reference" "C168"
			(at 0 0 90)
			(layer "F.SilkS")
			(hide yes)
			(effects
				(font
					(size 1.27 1.27)
				)
			)
		)
		(property "Value" "SC22U6D3V5MX-2GP"
			(at -0.0762 -6.1214 90)
			(unlocked yes)
			(layer "F.Fab")
			(hide yes)
			(effects
				(font
					(size 1.016 1.016)
					(thickness 0.1524)
				)
			)
		)
		(property "Device Type" "C805H58"
			(at -0.0762 -8.1534 90)
			(unlocked yes)
			(layer "F.Fab")
			(hide yes)
			(effects
				(font
					(size 1.016 1.016)
					(thickness 0.1524)
				)
			)
		)
		(duplicate_pad_numbers_are_jumpers no)
		(fp_line
			(start 0.6096 0)
			(end -0.6096 0)
			(stroke
				(width 0.3048)
				(type default)
			)
			(layer "F.SilkS")
		)
		(fp_poly
			(pts
				(xy -0.9017 1.4351) (xy 0.9017 1.4351) (xy 0.9017 -1.4351) (xy -0.9017 -1.4351)
			)
			(stroke
				(width 0)
				(type default)
			)
			(fill no)
			(layer "F.CrtYd")
		)
		(fp_poly
			(pts
				(xy 0.9271 1.4351) (xy 0.9271 -1.4351) (xy -0.8763 -1.4351) (xy -0.8763 1.4351)
			)
			(stroke
				(width 0)
				(type default)
			)
			(fill no)
			(layer "F.Fab")
		)
		(pad "1" smd rect
			(at 0 -0.8382 90)
			(size 1.5494 0.9398)
			(layers "F.Cu" "F.Mask" "F.Paste")
			(net "PVCCP")
		)
		(pad "2" smd rect
			(at 0 0.8382 90)
			(size 1.5494 0.9398)
			(layers "F.Cu" "F.Mask" "F.Paste")
			(net "GND")
		)
	)
	(footprint ""
		(layer "F.Cu")
		(at 58.0898 -13.7668)
		(property "Reference" "U34"
			(at 0 0 0)
			(layer "F.SilkS")
			(hide yes)
			(effects
				(font
					(size 1.27 1.27)
				)
			)
		)
		(property "Value" "2N7002DW-7F-GP"
			(at -2.5654 1.1049 0)
			(unlocked yes)
			(layer "F.Fab")
			(hide yes)
			(effects
				(font
					(size 1.016 1.016)
					(thickness 0.1524)
				)
			)
		)
		(property "Device Type" "SOT-363H44"
			(at -2.5654 -0.4191 0)
			(unlocked yes)
			(layer "F.Fab")
			(hide yes)
			(effects
				(font
					(size 1.016 1.016)
					(thickness 0.1524)
				)
			)
		)
		(duplicate_pad_numbers_are_jumpers no)
		(fp_poly
			(pts
				(xy -0.6731 1.4351) (xy -0.9779 1.7399) (xy -0.381 1.7399) (xy -0.3683 1.7399) (xy -0.381 1.7272)
			)
			(stroke
				(width 0)
				(type default)
			)
			(fill yes)
			(layer "F.SilkS")
		)
		(fp_poly
			(pts
				(xy 1.2573 0.8763) (xy 1.2573 -0.8763) (xy 0.9525 -0.8763) (xy 0.9525 -1.4351) (xy -0.9525 -1.4351)
				(xy -0.9525 -0.8763) (xy -1.2573 -0.8763) (xy -1.2573 0.8763) (xy -0.9525 0.8763) (xy -0.9525 1.4351)
				(xy 0.9525 1.4351) (xy 0.9525 0.8763)
			)
			(stroke
				(width 0)
				(type default)
			)
			(fill no)
			(layer "F.CrtYd")
		)
		(fp_poly
			(pts
				(xy 1.2573 0.8763) (xy 1.2573 -0.8763) (xy 0.9525 -0.8763) (xy 0.9525 -1.4351) (xy -0.9525 -1.4351)
				(xy -0.9525 -0.8763) (xy -1.2573 -0.8763) (xy -1.2573 0.8763) (xy -0.9525 0.8763) (xy -0.9525 1.4351)
				(xy 0.9525 1.4351) (xy 0.9525 0.8763)
			)
			(stroke
				(width 0)
				(type default)
			)
			(fill no)
			(layer "F.Fab")
		)
		(pad "1" smd rect
			(at -0.65024 0.8255)
			(size 0.3556 0.9652)
			(layers "F.Cu" "F.Mask" "F.Paste")
			(net "GBE_SMBCLK")
		)
		(pad "2" smd rect
			(at 0 0.8255)
			(size 0.3556 0.9652)
			(layers "F.Cu" "F.Mask" "F.Paste")
			(net "GF_GBE_SMB_SW_EN")
		)
		(pad "3" smd rect
			(at 0.65024 0.8255)
			(size 0.3556 0.9652)
			(layers "F.Cu" "F.Mask" "F.Paste")
			(net "GF_GBE_SMBDATA")
		)
		(pad "4" smd rect
			(at 0.65024 -0.8255)
			(size 0.3556 0.9652)
			(layers "F.Cu" "F.Mask" "F.Paste")
			(net "GBE_SMBDATA")
		)
		(pad "5" smd rect
			(at 0 -0.8255)
			(size 0.3556 0.9652)
			(layers "F.Cu" "F.Mask" "F.Paste")
			(net "GF_GBE_SMB_SW_EN")
		)
		(pad "6" smd rect
			(at -0.65024 -0.8255)
			(size 0.3556 0.9652)
			(layers "F.Cu" "F.Mask" "F.Paste")
			(net "GF_GBE_SMBCLK")
		)
	)
	(footprint ""
		(layer "F.Cu")
		(at 189.1538 -18.161 180)
		(property "Reference" "PC116"
			(at 0 0 180)
			(layer "F.SilkS")
			(hide yes)
			(effects
				(font
					(size 1.27 1.27)
				)
			)
		)
		(property "Value" "SCD1U16V2KX-3GP"
			(at 1.1811 -2.7051 180)
			(unlocked yes)
			(layer "F.Fab")
			(hide yes)
			(effects
				(font
					(size 1.016 1.016)
					(thickness 0.1524)
				)
			)
		)
		(property "Device Type" "C402H22"
			(at 1.1811 -4.2291 180)
			(unlocked yes)
			(layer "F.Fab")
			(hide yes)
			(effects
				(font
					(size 1.016 1.016)
					(thickness 0.1524)
				)
			)
		)
		(duplicate_pad_numbers_are_jumpers no)
		(fp_rect
			(start -0.381 0.7366)
			(end 0.381 -0.7366)
			(stroke
				(width 0)
				(type default)
			)
			(fill no)
			(layer "F.CrtYd")
		)
		(fp_rect
			(start -0.381 0.7366)
			(end 0.381 -0.7366)
			(stroke
				(width 0)
				(type default)
			)
			(fill no)
			(layer "F.Fab")
		)
		(pad "1" smd custom
			(at 0 -0.4572 180)
			(size 0.1143 0.1143)
			(layers "F.Cu" "F.Mask" "F.Paste")
			(net "PV_VTT_DDR_B_SNS")
			(options
				(clearance outline)
				(anchor circle)
			)
			(primitives
				(gr_poly
					(pts
						(arc
							(start -0.254 -0.1778)
							(mid -0.239121 -0.213721)
							(end -0.2032 -0.2286)
						)
						(arc
							(start 0.2032 -0.2286)
							(mid 0.239121 -0.213721)
							(end 0.254 -0.1778)
						)
						(arc
							(start 0.254 0.1778)
							(mid 0.239121 0.213721)
							(end 0.2032 0.2286)
						)
						(arc
							(start -0.2032 0.2286)
							(mid -0.239121 0.213721)
							(end -0.254 0.1778)
						)
					)
					(width 0)
					(fill yes)
				)
			)
		)
		(pad "2" smd custom
			(at 0 0.4572 180)
			(size 0.1143 0.1143)
			(layers "F.Cu" "F.Mask" "F.Paste")
			(net "GND")
			(options
				(clearance outline)
				(anchor circle)
			)
			(primitives
				(gr_poly
					(pts
						(arc
							(start -0.254 -0.1778)
							(mid -0.239121 -0.213721)
							(end -0.2032 -0.2286)
						)
						(arc
							(start 0.2032 -0.2286)
							(mid 0.239121 -0.213721)
							(end 0.254 -0.1778)
						)
						(arc
							(start 0.254 0.1778)
							(mid 0.239121 0.213721)
							(end 0.2032 0.2286)
						)
						(arc
							(start -0.2032 0.2286)
							(mid -0.239121 0.213721)
							(end -0.254 0.1778)
						)
					)
					(width 0)
					(fill yes)
				)
			)
		)
	)
	(footprint ""
		(layer "F.Cu")
		(at 21.9456 -52.0954)
		(property "Reference" "PC55"
			(at 0 0 0)
			(layer "F.SilkS")
			(hide yes)
			(effects
				(font
					(size 1.27 1.27)
				)
			)
		)
		(property "Value" "SCD22U10V2KX-1GP"
			(at 1.8923 -1.2065 0)
			(unlocked yes)
			(layer "F.Fab")
			(hide yes)
			(effects
				(font
					(size 1.016 1.016)
					(thickness 0.1524)
				)
			)
		)
		(property "Device Type" "C402H22"
			(at 1.8923 -2.7305 0)
			(unlocked yes)
			(layer "F.Fab")
			(hide yes)
			(effects
				(font
					(size 1.016 1.016)
					(thickness 0.1524)
				)
			)
		)
		(duplicate_pad_numbers_are_jumpers no)
		(fp_rect
			(start -0.381 0.7366)
			(end 0.381 -0.7366)
			(stroke
				(width 0)
				(type default)
			)
			(fill no)
			(layer "F.CrtYd")
		)
		(fp_rect
			(start -0.381 0.7366)
			(end 0.381 -0.7366)
			(stroke
				(width 0)
				(type default)
			)
			(fill no)
			(layer "F.Fab")
		)
		(pad "1" smd custom
			(at 0 -0.4572)
			(size 0.1143 0.1143)
			(layers "F.Cu" "F.Mask" "F.Paste")
			(net "VR_PVCCP_ISEN1_R")
			(options
				(clearance outline)
				(anchor circle)
			)
			(primitives
				(gr_poly
					(pts
						(arc
							(start -0.254 -0.1778)
							(mid -0.239121 -0.213721)
							(end -0.2032 -0.2286)
						)
						(arc
							(start 0.2032 -0.2286)
							(mid 0.239121 -0.213721)
							(end 0.254 -0.1778)
						)
						(arc
							(start 0.254 0.1778)
							(mid 0.239121 0.213721)
							(end 0.2032 0.2286)
						)
						(arc
							(start -0.2032 0.2286)
							(mid -0.239121 0.213721)
							(end -0.254 0.1778)
						)
					)
					(width 0)
					(fill yes)
				)
			)
		)
		(pad "2" smd custom
			(at 0 0.4572)
			(size 0.1143 0.1143)
			(layers "F.Cu" "F.Mask" "F.Paste")
			(net "VR_PVCCP_ISUMN")
			(options
				(clearance outline)
				(anchor circle)
			)
			(primitives
				(gr_poly
					(pts
						(arc
							(start -0.254 -0.1778)
							(mid -0.239121 -0.213721)
							(end -0.2032 -0.2286)
						)
						(arc
							(start 0.2032 -0.2286)
							(mid 0.239121 -0.213721)
							(end 0.254 -0.1778)
						)
						(arc
							(start 0.254 0.1778)
							(mid 0.239121 0.213721)
							(end 0.2032 0.2286)
						)
						(arc
							(start -0.2032 0.2286)
							(mid -0.239121 0.213721)
							(end -0.254 0.1778)
						)
					)
					(width 0)
					(fill yes)
				)
			)
		)
	)
	(footprint ""
		(layer "F.Cu")
		(at 189.0522 -27.4574 90)
		(property "Reference" "PC191"
			(at 0 0 90)
			(layer "F.SilkS")
			(hide yes)
			(effects
				(font
					(size 1.27 1.27)
				)
			)
		)
		(property "Value" "SC330P50V2KX-3GP"
			(at 1.8923 -1.2065 90)
			(unlocked yes)
			(layer "F.Fab")
			(hide yes)
			(effects
				(font
					(size 1.016 1.016)
					(thickness 0.1524)
				)
			)
		)
		(property "Device Type" "C402H22"
			(at 1.8923 -2.7305 90)
			(unlocked yes)
			(layer "F.Fab")
			(hide yes)
			(effects
				(font
					(size 1.016 1.016)
					(thickness 0.1524)
				)
			)
		)
		(duplicate_pad_numbers_are_jumpers no)
		(fp_rect
			(start -0.381 0.7366)
			(end 0.381 -0.7366)
			(stroke
				(width 0)
				(type default)
			)
			(fill no)
			(layer "F.CrtYd")
		)
		(fp_rect
			(start -0.381 0.7366)
			(end 0.381 -0.7366)
			(stroke
				(width 0)
				(type default)
			)
			(fill no)
			(layer "F.Fab")
		)
		(pad "1" smd custom
			(at 0 -0.4572 90)
			(size 0.1143 0.1143)
			(layers "F.Cu" "F.Mask" "F.Paste")
			(net "VR_PVDDR_A_SUMN")
			(options
				(clearance outline)
				(anchor circle)
			)
			(primitives
				(gr_poly
					(pts
						(arc
							(start -0.254 -0.1778)
							(mid -0.239121 -0.213721)
							(end -0.2032 -0.2286)
						)
						(arc
							(start 0.2032 -0.2286)
							(mid 0.239121 -0.213721)
							(end 0.254 -0.1778)
						)
						(arc
							(start 0.254 0.1778)
							(mid 0.239121 0.213721)
							(end 0.2032 0.2286)
						)
						(arc
							(start -0.2032 0.2286)
							(mid -0.239121 0.213721)
							(end -0.254 0.1778)
						)
					)
					(width 0)
					(fill yes)
				)
			)
		)
		(pad "2" smd custom
			(at 0 0.4572 90)
			(size 0.1143 0.1143)
			(layers "F.Cu" "F.Mask" "F.Paste")
			(net "VR_PVDDR_A_SUMN_C")
			(options
				(clearance outline)
				(anchor circle)
			)
			(primitives
				(gr_poly
					(pts
						(arc
							(start -0.254 -0.1778)
							(mid -0.239121 -0.213721)
							(end -0.2032 -0.2286)
						)
						(arc
							(start 0.2032 -0.2286)
							(mid 0.239121 -0.213721)
							(end 0.254 -0.1778)
						)
						(arc
							(start 0.254 0.1778)
							(mid 0.239121 0.213721)
							(end 0.2032 0.2286)
						)
						(arc
							(start -0.2032 0.2286)
							(mid -0.239121 0.213721)
							(end -0.254 0.1778)
						)
					)
					(width 0)
					(fill yes)
				)
			)
		)
	)
)
